# T6G (Grand Teton) — schematic netlist excerpt (pin names and nets, part order shuffled) for the footprints in the layout excerpt that follows; sources: Cadence DE-HDL packaged netlist, KiCad conversion of 04192023_DAF0TMB3IC0_F0TG_MB_C_brd_V02_OCP.brd

C466  Q_CAP  100UF 4V 20% X6S  pkg C0805  page 356 : A = P0V9_CPU1_RT3_2A ; B = GND
PC556_3  Q_CAP  22UF 16V 20% X6S  pkg C0805  page 195 : A = SW_P12V_AUX_PVDDCR_CPU0_P0_FLT ; B = GND
C6750  Q_CAP_DIFFBUS  DIFF BUS_0.22UF 6.3V 20% X6S  pkg C0201  page 352 : \1\ = P5E_CPU1_P3_TX_BUF_C_DN<12> ; \2\ = P5E_CPU1_P3_TX_BUF_DN<12>
C576  Q_CAP  0.1UF 10V 10% X7S  pkg C0201  page 279 : A = P0V9_CPU0_RT0_2A ; B = GND
C198  Q_CAP  0.1UF 10V 10% X7S  pkg C0201  page 323 : A = P0V9_CPU1_RT0_2A_2D ; B = GND

(kicad_pcb
	(version 20260206)
	(generator "pcbnew")
	(generator_version "10.0")
	(general
		(thickness 1.6)
		(legacy_teardrops no)
	)
	(paper "A4")
	(title_block
		(title "04192023_DAF0TMB3IC0_F0TG_MB_C_brd_V02_OCP.brd")
		(comment 1 "Grand Teton / footprints 5708-5712 of 8354")
	)
	(layers
		(0 "F.Cu" signal "TOP")
		(4 "In1.Cu" signal "GND")
		(6 "In2.Cu" signal "IN1")
		(8 "In3.Cu" signal "GND1")
		(10 "In4.Cu" signal "IN2")
		(12 "In5.Cu" signal "GND2")
		(14 "In6.Cu" signal "IN3")
		(16 "In7.Cu" signal "GND3")
		(18 "In8.Cu" signal "VCC")
		(20 "In9.Cu" signal "VCC1")
		(22 "In10.Cu" signal "GND4")
		(24 "In11.Cu" signal "IN4")
		(26 "In12.Cu" signal "GND5")
		(28 "In13.Cu" signal "IN5")
		(30 "In14.Cu" signal "GND6")
		(32 "In15.Cu" signal "IN6")
		(34 "In16.Cu" signal "GND7")
		(2 "B.Cu" signal "BOTTOM")
		(9 "F.Adhes" user "F.Adhesive")
		(11 "B.Adhes" user "B.Adhesive")
		(13 "F.Paste" user "Package Geometry/Pastemask Top")
		(15 "B.Paste" user "Package Geometry/Pastemask Bottom")
		(5 "F.SilkS" user "Ref Des/Silkscreen Top")
		(7 "B.SilkS" user "Ref Des/Silkscreen Bottom")
		(1 "F.Mask" user "Board Geometry/Soldermask Top")
		(3 "B.Mask" user "Board Geometry/Soldermask Bottom")
		(17 "Dwgs.User" user "User.Drawings")
		(19 "Cmts.User" user "User.Comments")
		(21 "Eco1.User" user "User.Eco1")
		(23 "Eco2.User" user "User.Eco2")
		(25 "Edge.Cuts" user "Board Geometry/Outline")
		(27 "Margin" user)
		(31 "F.CrtYd" user "Package Geometry/Place Bound Top")
		(29 "B.CrtYd" user "Package Geometry/Place Bound Bottom")
		(35 "F.Fab" user "Ref Des/Assembly Top")
		(33 "B.Fab" user "Ref Des/Assembly Bottom")
	)
	(footprint ""
		(layer "B.Cu")
		(at 136.936226 -390.073134 180)
		(property "Reference" "C466"
			(at 0 0 0)
			(layer "B.SilkS")
			(hide yes)
			(effects
				(font
					(size 1.27 1.27)
				)
				(justify mirror)
			)
		)
		(property "Value" ""
			(at 0 0 0)
			(layer "B.Fab")
			(effects
				(font
					(size 1.27 1.27)
				)
				(justify mirror)
			)
		)
		(duplicate_pad_numbers_are_jumpers no)
		(fp_line
			(start 1.524 0.762)
			(end 1.524 -0.762)
			(stroke
				(width 0.1524)
				(type default)
			)
			(layer "B.SilkS")
		)
		(fp_line
			(start 1.524 -0.762)
			(end -1.524 -0.762)
			(stroke
				(width 0.1524)
				(type default)
			)
			(layer "B.SilkS")
		)
		(fp_line
			(start -1.524 0.762)
			(end 1.524 0.762)
			(stroke
				(width 0.1524)
				(type default)
			)
			(layer "B.SilkS")
		)
		(fp_line
			(start -1.524 -0.762)
			(end -1.524 0.762)
			(stroke
				(width 0.1524)
				(type default)
			)
			(layer "B.SilkS")
		)
		(fp_line
			(start 1.1049 0.724916)
			(end -1.1049 0.724916)
			(stroke
				(width 0.1)
				(type default)
			)
			(layer "B.Fab")
		)
		(fp_line
			(start 1.1049 -0.724916)
			(end 1.1049 0.724916)
			(stroke
				(width 0.1)
				(type default)
			)
			(layer "B.Fab")
		)
		(fp_line
			(start -1.1049 0.724916)
			(end -1.1049 -0.724916)
			(stroke
				(width 0.1)
				(type default)
			)
			(layer "B.Fab")
		)
		(fp_line
			(start -1.1049 -0.724916)
			(end 1.1049 -0.724916)
			(stroke
				(width 0.1)
				(type default)
			)
			(layer "B.Fab")
		)
		(pad "1" smd rect
			(at 0.889 0 180)
			(size 1.016 1.27)
			(layers "B.Cu" "B.Mask" "B.Paste")
			(net "P0V9_CPU1_RT3_2A")
		)
		(pad "2" smd rect
			(at -0.889 0 180)
			(size 1.016 1.27)
			(layers "B.Cu" "B.Mask" "B.Paste")
			(net "GND")
		)
	)
	(footprint ""
		(layer "B.Cu")
		(at 153.159206 -408.517344 90)
		(property "Reference" "C6750"
			(at 0 0 90)
			(layer "B.SilkS")
			(hide yes)
			(effects
				(font
					(size 1.27 1.27)
				)
				(justify mirror)
			)
		)
		(property "Value" ""
			(at 0 0 90)
			(layer "B.Fab")
			(effects
				(font
					(size 1.27 1.27)
				)
				(justify mirror)
			)
		)
		(duplicate_pad_numbers_are_jumpers no)
		(fp_line
			(start 0.299974 -0.150114)
			(end -0.299974 -0.150114)
			(stroke
				(width 0.1)
				(type default)
			)
			(layer "B.Fab")
		)
		(fp_line
			(start -0.299974 -0.150114)
			(end -0.299974 0.150114)
			(stroke
				(width 0.1)
				(type default)
			)
			(layer "B.Fab")
		)
		(fp_line
			(start 0.299974 0.150114)
			(end 0.299974 -0.150114)
			(stroke
				(width 0.1)
				(type default)
			)
			(layer "B.Fab")
		)
		(fp_line
			(start -0.299974 0.150114)
			(end 0.299974 0.150114)
			(stroke
				(width 0.1)
				(type default)
			)
			(layer "B.Fab")
		)
		(pad "1" smd rect
			(at 0.2667 0 270)
			(size 0.3048 0.381)
			(layers "B.Cu" "B.Mask" "B.Paste")
			(net "P5E_CPU1_P3_TX_BUF_C_DN<12>")
		)
		(pad "2" smd rect
			(at -0.2667 0 270)
			(size 0.3048 0.381)
			(layers "B.Cu" "B.Mask" "B.Paste")
			(net "P5E_CPU1_P3_TX_BUF_DN<12>")
		)
	)
	(footprint ""
		(layer "B.Cu")
		(at 60.718446 -388.011162 -90)
		(property "Reference" "C198"
			(at 0 0 90)
			(layer "B.SilkS")
			(hide yes)
			(effects
				(font
					(size 1.27 1.27)
				)
				(justify mirror)
			)
		)
		(property "Value" ""
			(at 0 0 90)
			(layer "B.Fab")
			(effects
				(font
					(size 1.27 1.27)
				)
				(justify mirror)
			)
		)
		(duplicate_pad_numbers_are_jumpers no)
		(fp_line
			(start -0.299974 0.150114)
			(end 0.299974 0.150114)
			(stroke
				(width 0.1)
				(type default)
			)
			(layer "B.Fab")
		)
		(fp_line
			(start 0.299974 0.150114)
			(end 0.299974 -0.150114)
			(stroke
				(width 0.1)
				(type default)
			)
			(layer "B.Fab")
		)
		(fp_line
			(start -0.299974 -0.150114)
			(end -0.299974 0.150114)
			(stroke
				(width 0.1)
				(type default)
			)
			(layer "B.Fab")
		)
		(fp_line
			(start 0.299974 -0.150114)
			(end -0.299974 -0.150114)
			(stroke
				(width 0.1)
				(type default)
			)
			(layer "B.Fab")
		)
		(pad "1" smd rect
			(at 0.2667 0 90)
			(size 0.3048 0.381)
			(layers "B.Cu" "B.Mask" "B.Paste")
			(net "P0V9_CPU1_RT0_2A_2D")
		)
		(pad "2" smd rect
			(at -0.2667 0 90)
			(size 0.3048 0.381)
			(layers "B.Cu" "B.Mask" "B.Paste")
			(net "GND")
		)
	)
	(footprint ""
		(layer "B.Cu")
		(at 301.099728 -396.991078 90)
		(property "Reference" "C576"
			(at 0 0 90)
			(layer "B.SilkS")
			(hide yes)
			(effects
				(font
					(size 1.27 1.27)
				)
				(justify mirror)
			)
		)
		(property "Value" ""
			(at 0 0 90)
			(layer "B.Fab")
			(effects
				(font
					(size 1.27 1.27)
				)
				(justify mirror)
			)
		)
		(duplicate_pad_numbers_are_jumpers no)
		(fp_line
			(start 0.299974 -0.150114)
			(end -0.299974 -0.150114)
			(stroke
				(width 0.1)
				(type default)
			)
			(layer "B.Fab")
		)
		(fp_line
			(start -0.299974 -0.150114)
			(end -0.299974 0.150114)
			(stroke
				(width 0.1)
				(type default)
			)
			(layer "B.Fab")
		)
		(fp_line
			(start 0.299974 0.150114)
			(end 0.299974 -0.150114)
			(stroke
				(width 0.1)
				(type default)
			)
			(layer "B.Fab")
		)
		(fp_line
			(start -0.299974 0.150114)
			(end 0.299974 0.150114)
			(stroke
				(width 0.1)
				(type default)
			)
			(layer "B.Fab")
		)
		(pad "1" smd rect
			(at 0.2667 0 270)
			(size 0.3048 0.381)
			(layers "B.Cu" "B.Mask" "B.Paste")
			(net "P0V9_CPU0_RT0_2A")
		)
		(pad "2" smd rect
			(at -0.2667 0 270)
			(size 0.3048 0.381)
			(layers "B.Cu" "B.Mask" "B.Paste")
			(net "GND")
		)
	)
	(footprint ""
		(layer "B.Cu")
		(at 378.019056 -182.867554 -90)
		(property "Reference" "PC556_3"
			(at 0 0 90)
			(layer "B.SilkS")
			(hide yes)
			(effects
				(font
					(size 1.27 1.27)
				)
				(justify mirror)
			)
		)
		(property "Value" ""
			(at 0 0 90)
			(layer "B.Fab")
			(effects
				(font
					(size 1.27 1.27)
				)
				(justify mirror)
			)
		)
		(duplicate_pad_numbers_are_jumpers no)
		(fp_line
			(start -1.524 0.762)
			(end 1.524 0.762)
			(stroke
				(width 0.1524)
				(type default)
			)
			(layer "B.SilkS")
		)
		(fp_line
			(start 1.524 0.762)
			(end 1.524 -0.762)
			(stroke
				(width 0.1524)
				(type default)
			)
			(layer "B.SilkS")
		)
		(fp_line
			(start -1.524 -0.762)
			(end -1.524 0.762)
			(stroke
				(width 0.1524)
				(type default)
			)
			(layer "B.SilkS")
		)
		(fp_line
			(start 1.524 -0.762)
			(end -1.524 -0.762)
			(stroke
				(width 0.1524)
				(type default)
			)
			(layer "B.SilkS")
		)
		(fp_line
			(start -1.1049 0.724916)
			(end -1.1049 -0.724916)
			(stroke
				(width 0.1)
				(type default)
			)
			(layer "B.Fab")
		)
		(fp_line
			(start 1.1049 0.724916)
			(end -1.1049 0.724916)
			(stroke
				(width 0.1)
				(type default)
			)
			(layer "B.Fab")
		)
		(fp_line
			(start -1.1049 -0.724916)
			(end 1.1049 -0.724916)
			(stroke
				(width 0.1)
				(type default)
			)
			(layer "B.Fab")
		)
		(fp_line
			(start 1.1049 -0.724916)
			(end 1.1049 0.724916)
			(stroke
				(width 0.1)
				(type default)
			)
			(layer "B.Fab")
		)
		(pad "1" smd rect
			(at 0.889 0 270)
			(size 1.016 1.27)
			(layers "B.Cu" "B.Mask" "B.Paste")
			(net "SW_P12V_AUX_PVDDCR_CPU0_P0_FLT")
		)
		(pad "2" smd rect
			(at -0.889 0 270)
			(size 1.016 1.27)
			(layers "B.Cu" "B.Mask" "B.Paste")
			(net "GND")
		)
	)
)
